(kicad_pcb
	(version 20221018)
	(generator pcbnew)
	(general
    (thickness 1.518)
  )
	(paper "A4")
	(title_block
    (title "Kria K26 Devboard")
    (date "2024-03-26")
    (rev "1.2.5")
    (comment 1 "www.antmicro.com")
    (comment 2 "Antmicro Ltd.")
		(comment 9 "footprints 185-186 of 660")
	)
	(layers
    (0 "F.Cu" mixed)
    (1 "In1.Cu" power)
    (2 "In2.Cu" mixed)
    (3 "In3.Cu" power)
    (4 "In4.Cu" mixed)
    (5 "In5.Cu" power)
    (6 "In6.Cu" mixed)
    (31 "B.Cu" power)
    (32 "B.Adhes" user "B.Adhesive")
    (33 "F.Adhes" user "F.Adhesive")
    (34 "B.Paste" user)
    (35 "F.Paste" user)
    (36 "B.SilkS" user "B.Silkscreen")
    (37 "F.SilkS" user "F.Silkscreen")
    (38 "B.Mask" user)
    (39 "F.Mask" user)
    (40 "Dwgs.User" user "User.Drawings")
    (41 "Cmts.User" user "User.Comments")
    (42 "Eco1.User" user "User.Eco1")
    (43 "Eco2.User" user "User.Eco2")
    (44 "Edge.Cuts" user)
    (45 "Margin" user)
    (46 "B.CrtYd" user "B.Courtyard")
    (47 "F.CrtYd" user "F.Courtyard")
    (48 "B.Fab" user)
    (49 "F.Fab" user)
  )
	(footprint "kria-k26-devboard-footprints:QFN-48-1EP_7x7mm" (layer "F.Cu")
    (at 148.846 88.714 -90)
    (property "Author" "Antmicro")
    (property "License" "Apache-2.0")
    (property "MPN" "DP83867CRRGZR")
    (property "Manufacturer" "Texas Instruments")
    (property "Sheetfile" "eth.kicad_sch")
    (property "Sheetname" "Ethernet")
    (property "ki_description" "Robust, High Immunity 10/100/1000 Ethernet Physical Layer Transceiver")
    (property "ki_keywords" "SMT, ETHERNET, IC, TRANSCEIVER")
    (attr smd)
    (fp_text reference "U30" (at -4.834 2.236) (layer "F.SilkS")
        (effects (font (size 0.7 0.7) (thickness 0.15)) (justify left bottom))
    )
    (fp_text value "DP83867CR_VQFN" (at 0 5.749 -90) (layer "F.Fab") hide
        (effects (font (size 0.7 0.7) (thickness 0.15)) (justify left bottom))
    )
    (fp_text user "License: Apache-2.0" (at -4.1 9.45 -90) (layer "F.Fab") hide
        (effects (font (size 0.7 0.7) (thickness 0.15)) (justify left bottom))
    )
    (fp_text user "Author: Antmicro" (at -4.1 8.249 -90) (layer "F.Fab") hide
        (effects (font (size 0.7 0.7) (thickness 0.15)) (justify left bottom))
    )
    (fp_text user "${REFERENCE}" (at -4.1 7.05 -90) (layer "F.Fab") hide
        (effects (font (size 0.7 0.7) (thickness 0.15)) (justify left bottom))
    )
    (fp_line (start -3.6 -3.6) (end -3.6 -3)
      (stroke (width 0.15) (type solid)) (layer "F.SilkS"))
    (fp_line (start -3.6 3) (end -3.6 3.6)
      (stroke (width 0.15) (type solid)) (layer "F.SilkS"))
    (fp_line (start -3.6 3.6) (end -3 3.6)
      (stroke (width 0.15) (type solid)) (layer "F.SilkS"))
    (fp_line (start -3 -3.6) (end -3.6 -3.6)
      (stroke (width 0.15) (type solid)) (layer "F.SilkS"))
    (fp_line (start 3.6 -3.6) (end 3 -3.6)
      (stroke (width 0.15) (type solid)) (layer "F.SilkS"))
    (fp_line (start 3.6 -3) (end 3.6 -3.6)
      (stroke (width 0.15) (type solid)) (layer "F.SilkS"))
    (fp_line (start 3.6 3) (end 3.6 3.6)
      (stroke (width 0.15) (type solid)) (layer "F.SilkS"))
    (fp_line (start 3.6 3.6) (end 2.999 3.6)
      (stroke (width 0.15) (type solid)) (layer "F.SilkS"))
    (fp_circle (center -3.85 -3.1) (end -3.8 -3.1)
      (stroke (width 0.15) (type solid)) (fill solid) (layer "F.SilkS"))
    (fp_line (start -4.1 -3.1) (end -4.1 3.1)
      (stroke (width 0.05) (type solid)) (layer "F.CrtYd"))
    (fp_line (start -4.1 3.1) (end -3.8 3.1)
      (stroke (width 0.05) (type solid)) (layer "F.CrtYd"))
    (fp_line (start -4.05 -3.1) (end -4.1 -3.1)
      (stroke (width 0.05) (type solid)) (layer "F.CrtYd"))
    (fp_line (start -3.8 -3.8) (end -3.8 -3.1)
      (stroke (width 0.05) (type solid)) (layer "F.CrtYd"))
    (fp_line (start -3.8 -3.1) (end -4.05 -3.1)
      (stroke (width 0.05) (type solid)) (layer "F.CrtYd"))
    (fp_line (start -3.8 3.1) (end -3.8 3.8)
      (stroke (width 0.05) (type solid)) (layer "F.CrtYd"))
    (fp_line (start -3.8 3.8) (end -3.1 3.8)
      (stroke (width 0.05) (type solid)) (layer "F.CrtYd"))
    (fp_line (start -3.1 -4.1) (end -3.1 -3.8)
      (stroke (width 0.05) (type solid)) (layer "F.CrtYd"))
    (fp_line (start -3.1 -3.8) (end -3.8 -3.8)
      (stroke (width 0.05) (type solid)) (layer "F.CrtYd"))
    (fp_line (start -3.1 3.8) (end -3.1 4.1)
      (stroke (width 0.05) (type solid)) (layer "F.CrtYd"))
    (fp_line (start -3.1 4.1) (end 3.1 4.1)
      (stroke (width 0.05) (type solid)) (layer "F.CrtYd"))
    (fp_line (start 3.1 -4.1) (end -3.1 -4.1)
      (stroke (width 0.05) (type solid)) (layer "F.CrtYd"))
    (fp_line (start 3.1 -3.75) (end 3.1 -4.1)
      (stroke (width 0.05) (type solid)) (layer "F.CrtYd"))
    (fp_line (start 3.1 3.8) (end 3.8 3.8)
      (stroke (width 0.05) (type solid)) (layer "F.CrtYd"))
    (fp_line (start 3.1 4.1) (end 3.1 3.8)
      (stroke (width 0.05) (type solid)) (layer "F.CrtYd"))
    (fp_line (start 3.8 -3.75) (end 3.1 -3.75)
      (stroke (width 0.05) (type solid)) (layer "F.CrtYd"))
    (fp_line (start 3.8 -3.1) (end 3.8 -3.75)
      (stroke (width 0.05) (type solid)) (layer "F.CrtYd"))
    (fp_line (start 3.8 3.1) (end 4.1 3.1)
      (stroke (width 0.05) (type solid)) (layer "F.CrtYd"))
    (fp_line (start 3.8 3.8) (end 3.8 3.1)
      (stroke (width 0.05) (type solid)) (layer "F.CrtYd"))
    (fp_line (start 4.1 -3.1) (end 3.8 -3.1)
      (stroke (width 0.05) (type solid)) (layer "F.CrtYd"))
    (fp_line (start 4.1 3.1) (end 4.1 -3.1)
      (stroke (width 0.05) (type solid)) (layer "F.CrtYd"))
    (fp_line (start -2.95 -3.5) (end -3.5 -2.95)
      (stroke (width 0.15) (type solid)) (layer "F.Fab"))
    (fp_rect (start 3.531 3.531) (end -3.519 -3.519)
      (stroke (width 0.15) (type solid)) (fill none) (layer "F.Fab"))
    (pad "" smd roundrect (at -1.6 -1.6 270) (size 1.4 1.4) (layers "F.Paste") (roundrect_rratio 0.05))
    (pad "" smd roundrect (at -1.6 0 270) (size 1.4 1.4) (layers "F.Paste") (roundrect_rratio 0.05))
    (pad "" smd roundrect (at -1.6 1.6 270) (size 1.4 1.4) (layers "F.Paste") (roundrect_rratio 0.05))
    (pad "" smd roundrect (at 0 -1.6 270) (size 1.4 1.4) (layers "F.Paste") (roundrect_rratio 0.05))
    (pad "" smd roundrect (at 0 0 270) (size 1.4 1.4) (layers "F.Paste") (roundrect_rratio 0.05))
    (pad "" smd roundrect (at 0 1.6 270) (size 1.4 1.4) (layers "F.Paste") (roundrect_rratio 0.05))
    (pad "" smd roundrect (at 1.6 -1.6 270) (size 1.4 1.4) (layers "F.Paste") (roundrect_rratio 0.05))
    (pad "" smd roundrect (at 1.6 0 270) (size 1.4 1.4) (layers "F.Paste") (roundrect_rratio 0.05))
    (pad "" smd roundrect (at 1.6 1.6 270) (size 1.4 1.4) (layers "F.Paste") (roundrect_rratio 0.05))
    (pad "1" smd rect (at -3.476 -2.75 270) (size 0.85 0.28) (layers "F.Cu" "F.Paste" "F.Mask")
      (net 267 "/Ethernet/TD_A_P") (pinfunction "TD_P_A") (pintype "bidirectional"))
    (pad "2" smd rect (at -3.476 -2.25 270) (size 0.85 0.28) (layers "F.Cu" "F.Paste" "F.Mask")
      (net 268 "/Ethernet/TD_A_N") (pinfunction "TD_M_A") (pintype "bidirectional"))
    (pad "3" smd rect (at -3.476 -1.75 270) (size 0.85 0.28) (layers "F.Cu" "F.Paste" "F.Mask")
      (net 16 "PS_2V5") (pinfunction "VDDA2P5") (pintype "power_in"))
    (pad "4" smd rect (at -3.476 -1.25 270) (size 0.85 0.28) (layers "F.Cu" "F.Paste" "F.Mask")
      (net 269 "/Ethernet/TD_B_P") (pinfunction "TD_P_B") (pintype "bidirectional"))
    (pad "5" smd rect (at -3.476 -0.75 270) (size 0.85 0.28) (layers "F.Cu" "F.Paste" "F.Mask")
      (net 270 "/Ethernet/TD_B_N") (pinfunction "TD_M_B") (pintype "bidirectional"))
    (pad "6" smd rect (at -3.476 -0.25 270) (size 0.85 0.28) (layers "F.Cu" "F.Paste" "F.Mask")
      (net 19 "PS_1V0") (pinfunction "VDD1P0") (pintype "passive"))
    (pad "7" smd rect (at -3.476 0.248 270) (size 0.85 0.28) (layers "F.Cu" "F.Paste" "F.Mask")
      (net 271 "/Ethernet/TD_C_P") (pinfunction "TD_P_C") (pintype "bidirectional"))
    (pad "8" smd rect (at -3.476 0.748 270) (size 0.85 0.28) (layers "F.Cu" "F.Paste" "F.Mask")
      (net 272 "/Ethernet/TD_C_N") (pinfunction "TD_M_C") (pintype "bidirectional"))
    (pad "9" smd rect (at -3.476 1.249 270) (size 0.85 0.28) (layers "F.Cu" "F.Paste" "F.Mask")
      (net 16 "PS_2V5") (pinfunction "VDDA2P5") (pintype "passive"))
    (pad "10" smd rect (at -3.476 1.749 270) (size 0.85 0.28) (layers "F.Cu" "F.Paste" "F.Mask")
      (net 273 "/Ethernet/TD_D_P") (pinfunction "TD_P_D") (pintype "bidirectional"))
    (pad "11" smd rect (at -3.476 2.249 270) (size 0.85 0.28) (layers "F.Cu" "F.Paste" "F.Mask")
      (net 274 "/Ethernet/TD_D_N") (pinfunction "TD_M_D") (pintype "bidirectional"))
    (pad "12" smd rect (at -3.476 2.749 270) (size 0.85 0.28) (layers "F.Cu" "F.Paste" "F.Mask")
      (net 671 "Net-(U30-RBIAS)") (pinfunction "RBIAS") (pintype "passive"))
    (pad "13" smd rect (at -2.75 3.475 270) (size 0.28 0.85) (layers "F.Cu" "F.Paste" "F.Mask")
      (net 724 "unconnected-(U30-VDDA1P8-Pad13)") (pinfunction "VDDA1P8") (pintype "power_in+no_connect"))
    (pad "14" smd rect (at -2.25 3.475 270) (size 0.28 0.85) (layers "F.Cu" "F.Paste" "F.Mask")
      (net 725 "unconnected-(U30-X_O-Pad14)") (pinfunction "X_O") (pintype "bidirectional+no_connect"))
    (pad "15" smd rect (at -1.75 3.475 270) (size 0.28 0.85) (layers "F.Cu" "F.Paste" "F.Mask")
      (net 295 "/Ethernet/X_I") (pinfunction "X_I") (pintype "bidirectional"))
    (pad "16" smd rect (at -1.25 3.475 270) (size 0.28 0.85) (layers "F.Cu" "F.Paste" "F.Mask")
      (net 49 "/Ethernet/MIO76") (pinfunction "MDC") (pintype "input"))
    (pad "17" smd rect (at -0.75 3.475 270) (size 0.28 0.85) (layers "F.Cu" "F.Paste" "F.Mask")
      (net 50 "/Ethernet/MIO77") (pinfunction "MDIO") (pintype "bidirectional"))
    (pad "18" smd rect (at -0.25 3.475 270) (size 0.28 0.85) (layers "F.Cu" "F.Paste" "F.Mask")
      (net 726 "unconnected-(U30-CLK_OUT-Pad18)") (pinfunction "CLK_OUT") (pintype "output+no_connect"))
    (pad "19" smd rect (at 0.248 3.475 270) (size 0.28 0.85) (layers "F.Cu" "F.Paste" "F.Mask")
      (net 17 "PS_1V8") (pinfunction "VDDIO") (pintype "power_in"))
    (pad "20" smd rect (at 0.748 3.475 270) (size 0.28 0.85) (layers "F.Cu" "F.Paste" "F.Mask")
      (net 673 "Net-(U30-JTAG_CLK)") (pinfunction "JTAG_CLK") (pintype "input"))
    (pad "21" smd rect (at 1.249 3.475 270) (size 0.28 0.85) (layers "F.Cu" "F.Paste" "F.Mask")
      (net 727 "unconnected-(U30-JTAG_TDO-Pad21)") (pinfunction "JTAG_TDO") (pintype "output+no_connect"))
    (pad "22" smd rect (at 1.749 3.475 270) (size 0.28 0.85) (layers "F.Cu" "F.Paste" "F.Mask")
      (net 674 "Net-(U30-JTAG_TMS)") (pinfunction "JTAG_TMS") (pintype "input"))
    (pad "23" smd rect (at 2.249 3.475 270) (size 0.28 0.85) (layers "F.Cu" "F.Paste" "F.Mask")
      (net 672 "Net-(U30-JTAG_TDI)") (pinfunction "JTAG_TDI") (pintype "input"))
    (pad "24" smd rect (at 2.749 3.475 270) (size 0.28 0.85) (layers "F.Cu" "F.Paste" "F.Mask")
      (net 19 "PS_1V0") (pinfunction "VDD1P0") (pintype "power_in"))
    (pad "25" smd rect (at 3.475 2.749 270) (size 0.85 0.28) (layers "F.Cu" "F.Paste" "F.Mask")
      (net 33 "/Ethernet/MIO68") (pinfunction "TX_D3") (pintype "input"))
    (pad "26" smd rect (at 3.475 2.249 270) (size 0.85 0.28) (layers "F.Cu" "F.Paste" "F.Mask")
      (net 32 "/Ethernet/MIO67") (pinfunction "TX_D2") (pintype "input"))
    (pad "27" smd rect (at 3.475 1.749 270) (size 0.85 0.28) (layers "F.Cu" "F.Paste" "F.Mask")
      (net 36 "/Ethernet/MIO66") (pinfunction "TX_D1") (pintype "input"))
    (pad "28" smd rect (at 3.475 1.249 270) (size 0.85 0.28) (layers "F.Cu" "F.Paste" "F.Mask")
      (net 35 "/Ethernet/MIO65") (pinfunction "TX_D0") (pintype "input"))
    (pad "29" smd rect (at 3.475 0.748 270) (size 0.85 0.28) (layers "F.Cu" "F.Paste" "F.Mask")
      (net 25 "/Ethernet/MIO64") (pinfunction "GTX_CLK") (pintype "input"))
    (pad "30" smd rect (at 3.475 0.248 270) (size 0.85 0.28) (layers "F.Cu" "F.Paste" "F.Mask")
      (net 17 "PS_1V8") (pinfunction "VDDIO") (pintype "passive"))
    (pad "31" smd rect (at 3.475 -0.25 270) (size 0.85 0.28) (layers "F.Cu" "F.Paste" "F.Mask")
      (net 19 "PS_1V0") (pinfunction "VDD1P0") (pintype "passive"))
    (pad "32" smd rect (at 3.475 -0.75 270) (size 0.85 0.28) (layers "F.Cu" "F.Paste" "F.Mask")
      (net 29 "/Ethernet/MIO70") (pinfunction "RX_CLK") (pintype "output"))
    (pad "33" smd rect (at 3.475 -1.25 270) (size 0.85 0.28) (layers "F.Cu" "F.Paste" "F.Mask")
      (net 30 "/Ethernet/MIO71") (pinfunction "RX_D0") (pintype "output"))
    (pad "34" smd rect (at 3.475 -1.75 270) (size 0.85 0.28) (layers "F.Cu" "F.Paste" "F.Mask")
      (net 31 "/Ethernet/MIO72") (pinfunction "RX_D1") (pintype "output"))
    (pad "35" smd rect (at 3.475 -2.25 270) (size 0.85 0.28) (layers "F.Cu" "F.Paste" "F.Mask")
      (net 26 "/Ethernet/MIO73") (pinfunction "RX_D2") (pintype "output"))
    (pad "36" smd rect (at 3.475 -2.75 270) (size 0.85 0.28) (layers "F.Cu" "F.Paste" "F.Mask")
      (net 27 "/Ethernet/MIO74") (pinfunction "RX_D3") (pintype "output"))
    (pad "37" smd rect (at 2.749 -3.476 270) (size 0.28 0.85) (layers "F.Cu" "F.Paste" "F.Mask")
      (net 34 "/Ethernet/MIO69") (pinfunction "TX_EN_TX_CTRL") (pintype "input"))
    (pad "38" smd rect (at 2.249 -3.476 270) (size 0.28 0.85) (layers "F.Cu" "F.Paste" "F.Mask")
      (net 28 "/Ethernet/MIO75") (pinfunction "RX_DV_RX_CTRL") (pintype "output"))
    (pad "39" smd rect (at 1.749 -3.476 270) (size 0.28 0.85) (layers "F.Cu" "F.Paste" "F.Mask")
      (net 728 "unconnected-(U30-GPIO_0-Pad39)") (pinfunction "GPIO_0") (pintype "output+no_connect"))
    (pad "40" smd rect (at 1.249 -3.476 270) (size 0.28 0.85) (layers "F.Cu" "F.Paste" "F.Mask")
      (net 729 "unconnected-(U30-GPIO_1-Pad40)") (pinfunction "GPIO_1") (pintype "output+no_connect"))
    (pad "41" smd rect (at 0.748 -3.476 270) (size 0.28 0.85) (layers "F.Cu" "F.Paste" "F.Mask")
      (net 17 "PS_1V8") (pinfunction "VDDIO") (pintype "passive"))
    (pad "42" smd rect (at 0.248 -3.476 270) (size 0.28 0.85) (layers "F.Cu" "F.Paste" "F.Mask")
      (net 19 "PS_1V0") (pinfunction "VDD1P0") (pintype "passive"))
    (pad "43" smd rect (at -0.25 -3.476 270) (size 0.28 0.85) (layers "F.Cu" "F.Paste" "F.Mask")
      (net 176 "/Ethernet/~{ETH_RESET}") (pinfunction "RESET_N") (pintype "input"))
    (pad "44" smd rect (at -0.75 -3.476 270) (size 0.28 0.85) (layers "F.Cu" "F.Paste" "F.Mask")
      (net 670 "Net-(U30-INT_PWDN)") (pinfunction "INT_PWDN") (pintype "bidirectional"))
    (pad "45" smd rect (at -1.25 -3.476 270) (size 0.28 0.85) (layers "F.Cu" "F.Paste" "F.Mask")
      (net 51 "/Ethernet/LED2") (pinfunction "LED_2") (pintype "bidirectional"))
    (pad "46" smd rect (at -1.75 -3.476 270) (size 0.28 0.85) (layers "F.Cu" "F.Paste" "F.Mask")
      (net 730 "unconnected-(U30-LED_1-Pad46)") (pinfunction "LED_1") (pintype "bidirectional+no_connect"))
    (pad "47" smd rect (at -2.25 -3.476 270) (size 0.28 0.85) (layers "F.Cu" "F.Paste" "F.Mask")
      (net 364 "/Ethernet/LED0") (pinfunction "LED_0") (pintype "bidirectional"))
    (pad "48" smd rect (at -2.75 -3.476 270) (size 0.28 0.85) (layers "F.Cu" "F.Paste" "F.Mask")
      (net 731 "unconnected-(U30-VDDA1P8-Pad48)") (pinfunction "VDDA1P8") (pintype "power_in+no_connect"))
    (pad "49" smd rect (at 0 0 270) (size 5.15 5.15) (layers "F.Cu" "F.Mask")
      (net 1 "GND") (pinfunction "PAD") (pintype "power_in"))
  )
	(footprint "kria-k26-devboard-footprints:C_0402_1005Metric" (layer "F.Cu")
    (at 154.116622 89.167588)
    (descr "Capacitor SMD 0402")
    (tags "capacitor SMD 0402")
    (property "Author" "Antmicro")
    (property "Dielectric" "X5R")
    (property "License" "Apache-2.0")
    (property "MPN" "GRM155R61H104KE14D")
    (property "Manufacturer" "Murata")
    (property "Sheetfile" "eth.kicad_sch")
    (property "Sheetname" "Ethernet")
    (property "Val" "100n")
    (property "Voltage" "50V")
    (property "ki_description" " ")
    (attr smd)
    (fp_text reference "C108" (at 0.743378 -0.237588) (layer "F.SilkS")
        (effects (font (size 0.7 0.7) (thickness 0.15)) (justify left bottom))
    )
    (fp_text value "C_100n_0402" (at 0 1.4) (layer "F.Fab") hide
        (effects (font (size 0.7 0.7) (thickness 0.15)) (justify left bottom))
    )
    (fp_text user "${REFERENCE}" (at -0.932 3.168) (layer "F.Fab") hide
        (effects (font (size 0.7 0.7) (thickness 0.15)) (justify left bottom))
    )
    (fp_text user "License: Apache-2.0" (at -0.932 5.17) (layer "F.Fab") hide
        (effects (font (size 0.7 0.7) (thickness 0.15)) (justify left bottom))
    )
    (fp_text user "Author: Antmicro" (at -0.932 4.17) (layer "F.Fab") hide
        (effects (font (size 0.7 0.7) (thickness 0.15)) (justify left bottom))
    )
    (fp_rect (start -0.94 -0.47) (end 0.94 0.47)
      (stroke (width 0.05) (type solid)) (fill none) (layer "F.CrtYd"))
    (fp_rect (start -0.499 -0.249) (end 0.499 0.249)
      (stroke (width 0.15) (type solid)) (fill none) (layer "F.Fab"))
    (pad "1" smd roundrect (at -0.484 0) (size 0.59 0.64) (layers "F.Cu" "F.Paste" "F.Mask") (roundrect_rratio 0.25)
      (net 19 "PS_1V0") (pintype "passive"))
    (pad "2" smd roundrect (at 0.484 0) (size 0.59 0.64) (layers "F.Cu" "F.Paste" "F.Mask") (roundrect_rratio 0.25)
      (net 1 "GND") (pintype "passive"))
  )
)
